# S9S_MB_2U (Grand Teton) — schematic netlist excerpt (pin names and nets, part order shuffled) for the footprints in the layout excerpt that follows; sources: Cadence DE-HDL packaged netlist, KiCad conversion of 03242023_DA0F0TMBIJ0_F0T_Motherboard_J_brd_V01_OCP.brd

PR141  Q_RES  2.2 1% CHIP  pkg 0402LF  page 269 : A = PVCCIN_CPU0_PVCC ; B = PVCCIN_CPU0_VDD5
R1757  Q_RES  33.2 1% CHIP  pkg 0402LF  page 222 : A = SGPIO_DI_1 ; B = SGPIO_BMC_DIN_R

(kicad_pcb
	(version 20260206)
	(generator "pcbnew")
	(generator_version "10.0")
	(general
		(thickness 1.6)
		(legacy_teardrops no)
	)
	(paper "A4")
	(title_block
		(title "03242023_DA0F0TMBIJ0_F0T_Motherboard_J_brd_V01_OCP.brd")
		(comment 1 "Grand Teton / footprints 5513-5514 of 6105")
	)
	(layers
		(0 "F.Cu" signal "TOP")
		(4 "In1.Cu" signal "GND")
		(6 "In2.Cu" signal "IN1")
		(8 "In3.Cu" signal "GND1")
		(10 "In4.Cu" signal "IN2")
		(12 "In5.Cu" signal "GND2")
		(14 "In6.Cu" signal "IN3")
		(16 "In7.Cu" signal "GND3")
		(18 "In8.Cu" signal "VCC")
		(20 "In9.Cu" signal "VCC1")
		(22 "In10.Cu" signal "GND4")
		(24 "In11.Cu" signal "IN4")
		(26 "In12.Cu" signal "GND5")
		(28 "In13.Cu" signal "IN5")
		(30 "In14.Cu" signal "GND6")
		(32 "In15.Cu" signal "IN6")
		(34 "In16.Cu" signal "GND7")
		(2 "B.Cu" signal "BOTTOM")
		(9 "F.Adhes" user "F.Adhesive")
		(11 "B.Adhes" user "B.Adhesive")
		(13 "F.Paste" user "Package Geometry/Pastemask Top")
		(15 "B.Paste" user "Package Geometry/Pastemask Bottom")
		(5 "F.SilkS" user "Ref Des/Silkscreen Top")
		(7 "B.SilkS" user "Ref Des/Silkscreen Bottom")
		(1 "F.Mask" user "Board Geometry/Soldermask Top")
		(3 "B.Mask" user "Board Geometry/Soldermask Bottom")
		(17 "Dwgs.User" user "User.Drawings")
		(19 "Cmts.User" user "User.Comments")
		(21 "Eco1.User" user "User.Eco1")
		(23 "Eco2.User" user "User.Eco2")
		(25 "Edge.Cuts" user "Board Geometry/Outline")
		(27 "Margin" user)
		(31 "F.CrtYd" user "Package Geometry/Place Bound Top")
		(29 "B.CrtYd" user "Package Geometry/Place Bound Bottom")
		(35 "F.Fab" user "Ref Des/Assembly Top")
		(33 "B.Fab" user "Ref Des/Assembly Bottom")
	)
	(footprint ""
		(layer "B.Cu")
		(at 375.197116 -338.098892 -90)
		(property "Reference" "PR141"
			(at 0 0 90)
			(layer "B.SilkS")
			(hide yes)
			(effects
				(font
					(size 1.27 1.27)
				)
				(justify mirror)
			)
		)
		(property "Value" ""
			(at 0 0 90)
			(layer "B.Fab")
			(effects
				(font
					(size 1.27 1.27)
				)
				(justify mirror)
			)
		)
		(duplicate_pad_numbers_are_jumpers no)
		(fp_line
			(start -0.7874 0.4064)
			(end 0.7874 0.4064)
			(stroke
				(width 0.1524)
				(type default)
			)
			(layer "B.SilkS")
		)
		(fp_line
			(start 0.7874 0.4064)
			(end 0.7874 -0.4064)
			(stroke
				(width 0.1524)
				(type default)
			)
			(layer "B.SilkS")
		)
		(fp_line
			(start -0.7874 -0.4064)
			(end -0.7874 0.4064)
			(stroke
				(width 0.1524)
				(type default)
			)
			(layer "B.SilkS")
		)
		(fp_line
			(start 0.7874 -0.4064)
			(end -0.7874 -0.4064)
			(stroke
				(width 0.1524)
				(type default)
			)
			(layer "B.SilkS")
		)
		(fp_line
			(start -0.67945 0.3048)
			(end -0.120396 0.3048)
			(stroke
				(width 0.1)
				(type default)
			)
			(layer "B.Fab")
		)
		(fp_line
			(start -0.120396 0.3048)
			(end -0.120396 0.2794)
			(stroke
				(width 0.1)
				(type default)
			)
			(layer "B.Fab")
		)
		(fp_line
			(start 0.12065 0.3048)
			(end 0.67945 0.3048)
			(stroke
				(width 0.1)
				(type default)
			)
			(layer "B.Fab")
		)
		(fp_line
			(start 0.67945 0.3048)
			(end 0.67945 -0.305054)
			(stroke
				(width 0.1)
				(type default)
			)
			(layer "B.Fab")
		)
		(fp_line
			(start -0.120396 0.2794)
			(end 0.12065 0.2794)
			(stroke
				(width 0.1)
				(type default)
			)
			(layer "B.Fab")
		)
		(fp_line
			(start 0.12065 0.2794)
			(end 0.12065 0.3048)
			(stroke
				(width 0.1)
				(type default)
			)
			(layer "B.Fab")
		)
		(fp_line
			(start -0.12065 -0.2794)
			(end -0.12065 -0.3048)
			(stroke
				(width 0.1)
				(type default)
			)
			(layer "B.Fab")
		)
		(fp_line
			(start 0.12065 -0.2794)
			(end -0.12065 -0.2794)
			(stroke
				(width 0.1)
				(type default)
			)
			(layer "B.Fab")
		)
		(fp_line
			(start -0.67945 -0.3048)
			(end -0.67945 0.3048)
			(stroke
				(width 0.1)
				(type default)
			)
			(layer "B.Fab")
		)
		(fp_line
			(start -0.12065 -0.3048)
			(end -0.67945 -0.3048)
			(stroke
				(width 0.1)
				(type default)
			)
			(layer "B.Fab")
		)
		(fp_line
			(start 0.12065 -0.305054)
			(end 0.12065 -0.2794)
			(stroke
				(width 0.1)
				(type default)
			)
			(layer "B.Fab")
		)
		(fp_line
			(start 0.67945 -0.305054)
			(end 0.12065 -0.305054)
			(stroke
				(width 0.1)
				(type default)
			)
			(layer "B.Fab")
		)
		(pad "1" smd circle
			(at 0.40005 0 90)
			(size 0 0)
			(layers "B.Cu" "B.Mask" "B.Paste")
			(net "PVCCIN_CPU0_PVCC")
		)
		(pad "2" smd circle
			(at -0.40005 0 90)
			(size 0 0)
			(layers "B.Cu" "B.Mask" "B.Paste")
			(net "PVCCIN_CPU0_VDD5")
		)
	)
	(footprint ""
		(layer "B.Cu")
		(at 157.02788 -117.566948 180)
		(property "Reference" "R1757"
			(at 0 0 0)
			(layer "B.SilkS")
			(hide yes)
			(effects
				(font
					(size 1.27 1.27)
				)
				(justify mirror)
			)
		)
		(property "Value" ""
			(at 0 0 0)
			(layer "B.Fab")
			(effects
				(font
					(size 1.27 1.27)
				)
				(justify mirror)
			)
		)
		(duplicate_pad_numbers_are_jumpers no)
		(fp_line
			(start 0.7874 0.4064)
			(end 0.7874 -0.4064)
			(stroke
				(width 0.1524)
				(type default)
			)
			(layer "B.SilkS")
		)
		(fp_line
			(start 0.7874 -0.4064)
			(end -0.7874 -0.4064)
			(stroke
				(width 0.1524)
				(type default)
			)
			(layer "B.SilkS")
		)
		(fp_line
			(start -0.7874 0.4064)
			(end 0.7874 0.4064)
			(stroke
				(width 0.1524)
				(type default)
			)
			(layer "B.SilkS")
		)
		(fp_line
			(start -0.7874 -0.4064)
			(end -0.7874 0.4064)
			(stroke
				(width 0.1524)
				(type default)
			)
			(layer "B.SilkS")
		)
		(fp_line
			(start 0.67945 0.3048)
			(end 0.67945 -0.305054)
			(stroke
				(width 0.1)
				(type default)
			)
			(layer "B.Fab")
		)
		(fp_line
			(start 0.67945 -0.305054)
			(end 0.12065 -0.305054)
			(stroke
				(width 0.1)
				(type default)
			)
			(layer "B.Fab")
		)
		(fp_line
			(start 0.12065 0.3048)
			(end 0.67945 0.3048)
			(stroke
				(width 0.1)
				(type default)
			)
			(layer "B.Fab")
		)
		(fp_line
			(start 0.12065 0.2794)
			(end 0.12065 0.3048)
			(stroke
				(width 0.1)
				(type default)
			)
			(layer "B.Fab")
		)
		(fp_line
			(start 0.12065 -0.2794)
			(end -0.12065 -0.2794)
			(stroke
				(width 0.1)
				(type default)
			)
			(layer "B.Fab")
		)
		(fp_line
			(start 0.12065 -0.305054)
			(end 0.12065 -0.2794)
			(stroke
				(width 0.1)
				(type default)
			)
			(layer "B.Fab")
		)
		(fp_line
			(start -0.120396 0.3048)
			(end -0.120396 0.2794)
			(stroke
				(width 0.1)
				(type default)
			)
			(layer "B.Fab")
		)
		(fp_line
			(start -0.120396 0.2794)
			(end 0.12065 0.2794)
			(stroke
				(width 0.1)
				(type default)
			)
			(layer "B.Fab")
		)
		(fp_line
			(start -0.12065 -0.2794)
			(end -0.12065 -0.3048)
			(stroke
				(width 0.1)
				(type default)
			)
			(layer "B.Fab")
		)
		(fp_line
			(start -0.12065 -0.3048)
			(end -0.67945 -0.3048)
			(stroke
				(width 0.1)
				(type default)
			)
			(layer "B.Fab")
		)
		(fp_line
			(start -0.67945 0.3048)
			(end -0.120396 0.3048)
			(stroke
				(width 0.1)
				(type default)
			)
			(layer "B.Fab")
		)
		(fp_line
			(start -0.67945 -0.3048)
			(end -0.67945 0.3048)
			(stroke
				(width 0.1)
				(type default)
			)
			(layer "B.Fab")
		)
		(pad "1" smd circle
			(at 0.40005 0)
			(size 0 0)
			(layers "B.Cu" "B.Mask" "B.Paste")
			(net "SGPIO_DI_1")
		)
		(pad "2" smd circle
			(at -0.40005 0)
			(size 0 0)
			(layers "B.Cu" "B.Mask" "B.Paste")
			(net "SGPIO_BMC_DIN_R")
		)
	)
)
